#ISCELL
  mstr_symbols design_note *
  *
#ISCELL
  mstr_symbols intel_corp_bpage *
  *
#CELL
  mstr_discrete res *
  page178_i1
#ISCELL
  mstr_standard offpage *
  page178_i10
#CELL
  mstr_discrete res *
  page178_i11
#CELL
  mstr_discrete res *
  page178_i12
#CELL
  mstr_discrete res *
  page178_i13
#ISCELL
  mstr_standard offpage *
  page178_i14
#ISCELL
  mstr_standard offpage *
  page178_i15
#ISCELL
  mstr_standard offpage *
  page178_i16
#CELL
  mstr_discrete res *
  page178_i17
#CELL
  mstr_discrete res *
  page178_i18
#ISCELL
  mstr_symbols p3v3_stby *
  page178_i19
#CELL
  mstr_discrete res *
  page178_i2
#CELL
  mstr_discrete res *
  page178_i20
#CELL
  mstr_discrete res *
  page178_i21
#CELL
  mstr_discrete res *
  page178_i22
#CELL
  mstr_discrete res *
  page178_i23
#ISCELL
  mstr_standard offpage *
  page178_i24
#ISCELL
  mstr_standard offpage *
  page178_i25
#ISCELL
  mstr_standard offpage *
  page178_i26
#ISCELL
  mstr_standard offpage *
  page178_i3
#ISCELL
  mstr_standard offpage *
  page178_i4
#ISCELL
  mstr_symbols p3v3_stby *
  page178_i5
#ISCELL
  mstr_standard offpage *
  page178_i6
#ISCELL
  mstr_standard offpage *
  page178_i7
#CELL
  mstr_discrete res *
  page178_i8
#ISCELL
  mstr_standard offpage *
  page178_i9
